# S9S_MB_2U (Grand Teton) — schematic netlist excerpt (pin names and nets, part order shuffled) for the footprints in the layout excerpt that follows; sources: Cadence DE-HDL packaged netlist, KiCad conversion of 03242023_DA0F0TMBIJ0_F0T_Motherboard_J_brd_V01_OCP.brd

R2243  Q_RES  1K 1% CHIP  pkg 0402LF  page 195 : A = FM_BOARD_SKU_ID0 ; B = GND
R4500  Q_RES  10K 1% EMPTY  pkg 0402LF  page 237 : A = P3V3 ; B = PU_CLK_BUF_ISO_EN
C1550  Q_CAP_DIFFBUS  DIFF BUS_0.22UF 6.3V 20% X6S  pkg C0201  page 175 : \1\ = P5E_CPU0_PE4_TX_C_DN<14> ; \2\ = P5E_CPU0_PE4_TX_DN<14>

(kicad_pcb
	(version 20260206)
	(generator "pcbnew")
	(generator_version "10.0")
	(general
		(thickness 1.6)
		(legacy_teardrops no)
	)
	(paper "A4")
	(title_block
		(title "03242023_DA0F0TMBIJ0_F0T_Motherboard_J_brd_V01_OCP.brd")
		(comment 1 "Grand Teton / footprints 2913-2915 of 6105")
	)
	(layers
		(0 "F.Cu" signal "TOP")
		(4 "In1.Cu" signal "GND")
		(6 "In2.Cu" signal "IN1")
		(8 "In3.Cu" signal "GND1")
		(10 "In4.Cu" signal "IN2")
		(12 "In5.Cu" signal "GND2")
		(14 "In6.Cu" signal "IN3")
		(16 "In7.Cu" signal "GND3")
		(18 "In8.Cu" signal "VCC")
		(20 "In9.Cu" signal "VCC1")
		(22 "In10.Cu" signal "GND4")
		(24 "In11.Cu" signal "IN4")
		(26 "In12.Cu" signal "GND5")
		(28 "In13.Cu" signal "IN5")
		(30 "In14.Cu" signal "GND6")
		(32 "In15.Cu" signal "IN6")
		(34 "In16.Cu" signal "GND7")
		(2 "B.Cu" signal "BOTTOM")
		(9 "F.Adhes" user "F.Adhesive")
		(11 "B.Adhes" user "B.Adhesive")
		(13 "F.Paste" user "Package Geometry/Pastemask Top")
		(15 "B.Paste" user "Package Geometry/Pastemask Bottom")
		(5 "F.SilkS" user "Ref Des/Silkscreen Top")
		(7 "B.SilkS" user "Ref Des/Silkscreen Bottom")
		(1 "F.Mask" user "Board Geometry/Soldermask Top")
		(3 "B.Mask" user "Board Geometry/Soldermask Bottom")
		(17 "Dwgs.User" user "User.Drawings")
		(19 "Cmts.User" user "User.Comments")
		(21 "Eco1.User" user "User.Eco1")
		(23 "Eco2.User" user "User.Eco2")
		(25 "Edge.Cuts" user "Board Geometry/Outline")
		(27 "Margin" user)
		(31 "F.CrtYd" user "Package Geometry/Place Bound Top")
		(29 "B.CrtYd" user "Package Geometry/Place Bound Bottom")
		(35 "F.Fab" user "Ref Des/Assembly Top")
		(33 "B.Fab" user "Ref Des/Assembly Bottom")
	)
	(footprint ""
		(layer "F.Cu")
		(at 346.840048 -402.371052 -90)
		(property "Reference" "C1550"
			(at 0 0 270)
			(layer "F.SilkS")
			(hide yes)
			(effects
				(font
					(size 1.27 1.27)
				)
			)
		)
		(property "Value" ""
			(at 0 0 270)
			(layer "F.Fab")
			(effects
				(font
					(size 1.27 1.27)
				)
			)
		)
		(duplicate_pad_numbers_are_jumpers no)
		(fp_line
			(start -0.299974 0.150114)
			(end -0.299974 -0.150114)
			(stroke
				(width 0.1)
				(type default)
			)
			(layer "F.Fab")
		)
		(fp_line
			(start 0.299974 0.150114)
			(end -0.299974 0.150114)
			(stroke
				(width 0.1)
				(type default)
			)
			(layer "F.Fab")
		)
		(fp_line
			(start -0.299974 -0.150114)
			(end 0.299974 -0.150114)
			(stroke
				(width 0.1)
				(type default)
			)
			(layer "F.Fab")
		)
		(fp_line
			(start 0.299974 -0.150114)
			(end 0.299974 0.150114)
			(stroke
				(width 0.1)
				(type default)
			)
			(layer "F.Fab")
		)
		(pad "1" smd rect
			(at -0.2667 0 270)
			(size 0.3048 0.381)
			(layers "F.Cu" "F.Mask" "F.Paste")
			(net "P5E_CPU0_PE4_TX_C_DN<14>")
		)
		(pad "2" smd rect
			(at 0.2667 0 270)
			(size 0.3048 0.381)
			(layers "F.Cu" "F.Mask" "F.Paste")
			(net "P5E_CPU0_PE4_TX_DN<14>")
		)
	)
	(footprint ""
		(layer "F.Cu")
		(at 317.7921 -76.585064 90)
		(property "Reference" "R2243"
			(at 0 0 90)
			(layer "F.SilkS")
			(hide yes)
			(effects
				(font
					(size 1.27 1.27)
				)
			)
		)
		(property "Value" ""
			(at 0 0 90)
			(layer "F.Fab")
			(effects
				(font
					(size 1.27 1.27)
				)
			)
		)
		(duplicate_pad_numbers_are_jumpers no)
		(fp_line
			(start 0.7874 -0.4064)
			(end 0.7874 0.4064)
			(stroke
				(width 0.1524)
				(type default)
			)
			(layer "F.SilkS")
		)
		(fp_line
			(start -0.7874 -0.4064)
			(end 0.7874 -0.4064)
			(stroke
				(width 0.1524)
				(type default)
			)
			(layer "F.SilkS")
		)
		(fp_line
			(start 0.7874 0.4064)
			(end -0.7874 0.4064)
			(stroke
				(width 0.1524)
				(type default)
			)
			(layer "F.SilkS")
		)
		(fp_line
			(start -0.7874 0.4064)
			(end -0.7874 -0.4064)
			(stroke
				(width 0.1524)
				(type default)
			)
			(layer "F.SilkS")
		)
		(fp_line
			(start -0.12065 -0.305054)
			(end -0.12065 -0.2794)
			(stroke
				(width 0.1)
				(type default)
			)
			(layer "F.Fab")
		)
		(fp_line
			(start -0.67945 -0.305054)
			(end -0.12065 -0.305054)
			(stroke
				(width 0.1)
				(type default)
			)
			(layer "F.Fab")
		)
		(fp_line
			(start 0.67945 -0.3048)
			(end 0.67945 0.3048)
			(stroke
				(width 0.1)
				(type default)
			)
			(layer "F.Fab")
		)
		(fp_line
			(start 0.12065 -0.3048)
			(end 0.67945 -0.3048)
			(stroke
				(width 0.1)
				(type default)
			)
			(layer "F.Fab")
		)
		(fp_line
			(start 0.12065 -0.2794)
			(end 0.12065 -0.3048)
			(stroke
				(width 0.1)
				(type default)
			)
			(layer "F.Fab")
		)
		(fp_line
			(start -0.12065 -0.2794)
			(end 0.12065 -0.2794)
			(stroke
				(width 0.1)
				(type default)
			)
			(layer "F.Fab")
		)
		(fp_line
			(start 0.120396 0.2794)
			(end -0.12065 0.2794)
			(stroke
				(width 0.1)
				(type default)
			)
			(layer "F.Fab")
		)
		(fp_line
			(start -0.12065 0.2794)
			(end -0.12065 0.3048)
			(stroke
				(width 0.1)
				(type default)
			)
			(layer "F.Fab")
		)
		(fp_line
			(start 0.67945 0.3048)
			(end 0.120396 0.3048)
			(stroke
				(width 0.1)
				(type default)
			)
			(layer "F.Fab")
		)
		(fp_line
			(start 0.120396 0.3048)
			(end 0.120396 0.2794)
			(stroke
				(width 0.1)
				(type default)
			)
			(layer "F.Fab")
		)
		(fp_line
			(start -0.12065 0.3048)
			(end -0.67945 0.3048)
			(stroke
				(width 0.1)
				(type default)
			)
			(layer "F.Fab")
		)
		(fp_line
			(start -0.67945 0.3048)
			(end -0.67945 -0.305054)
			(stroke
				(width 0.1)
				(type default)
			)
			(layer "F.Fab")
		)
		(pad "1" smd circle
			(at -0.40005 0 90)
			(size 0 0)
			(layers "F.Cu" "F.Mask" "F.Paste")
			(net "FM_BOARD_SKU_ID0")
		)
		(pad "2" smd circle
			(at 0.40005 0 90)
			(size 0 0)
			(layers "F.Cu" "F.Mask" "F.Paste")
			(net "GND")
		)
	)
	(footprint ""
		(layer "F.Cu")
		(at 265.172952 -127.548894)
		(property "Reference" "R4500"
			(at 0 0 0)
			(layer "F.SilkS")
			(hide yes)
			(effects
				(font
					(size 1.27 1.27)
				)
			)
		)
		(property "Value" ""
			(at 0 0 0)
			(layer "F.Fab")
			(effects
				(font
					(size 1.27 1.27)
				)
			)
		)
		(duplicate_pad_numbers_are_jumpers no)
		(fp_line
			(start -0.7874 -0.4064)
			(end 0.7874 -0.4064)
			(stroke
				(width 0.1524)
				(type default)
			)
			(layer "F.SilkS")
		)
		(fp_line
			(start -0.7874 0.4064)
			(end -0.7874 -0.4064)
			(stroke
				(width 0.1524)
				(type default)
			)
			(layer "F.SilkS")
		)
		(fp_line
			(start 0.7874 -0.4064)
			(end 0.7874 0.4064)
			(stroke
				(width 0.1524)
				(type default)
			)
			(layer "F.SilkS")
		)
		(fp_line
			(start 0.7874 0.4064)
			(end -0.7874 0.4064)
			(stroke
				(width 0.1524)
				(type default)
			)
			(layer "F.SilkS")
		)
		(fp_line
			(start -0.67945 -0.305054)
			(end -0.12065 -0.305054)
			(stroke
				(width 0.1)
				(type default)
			)
			(layer "F.Fab")
		)
		(fp_line
			(start -0.67945 0.3048)
			(end -0.67945 -0.305054)
			(stroke
				(width 0.1)
				(type default)
			)
			(layer "F.Fab")
		)
		(fp_line
			(start -0.12065 -0.305054)
			(end -0.12065 -0.2794)
			(stroke
				(width 0.1)
				(type default)
			)
			(layer "F.Fab")
		)
		(fp_line
			(start -0.12065 -0.2794)
			(end 0.12065 -0.2794)
			(stroke
				(width 0.1)
				(type default)
			)
			(layer "F.Fab")
		)
		(fp_line
			(start -0.12065 0.2794)
			(end -0.12065 0.3048)
			(stroke
				(width 0.1)
				(type default)
			)
			(layer "F.Fab")
		)
		(fp_line
			(start -0.12065 0.3048)
			(end -0.67945 0.3048)
			(stroke
				(width 0.1)
				(type default)
			)
			(layer "F.Fab")
		)
		(fp_line
			(start 0.120396 0.2794)
			(end -0.12065 0.2794)
			(stroke
				(width 0.1)
				(type default)
			)
			(layer "F.Fab")
		)
		(fp_line
			(start 0.120396 0.3048)
			(end 0.120396 0.2794)
			(stroke
				(width 0.1)
				(type default)
			)
			(layer "F.Fab")
		)
		(fp_line
			(start 0.12065 -0.3048)
			(end 0.67945 -0.3048)
			(stroke
				(width 0.1)
				(type default)
			)
			(layer "F.Fab")
		)
		(fp_line
			(start 0.12065 -0.2794)
			(end 0.12065 -0.3048)
			(stroke
				(width 0.1)
				(type default)
			)
			(layer "F.Fab")
		)
		(fp_line
			(start 0.67945 -0.3048)
			(end 0.67945 0.3048)
			(stroke
				(width 0.1)
				(type default)
			)
			(layer "F.Fab")
		)
		(fp_line
			(start 0.67945 0.3048)
			(end 0.120396 0.3048)
			(stroke
				(width 0.1)
				(type default)
			)
			(layer "F.Fab")
		)
		(pad "1" smd circle
			(at -0.40005 0)
			(size 0 0)
			(layers "F.Cu" "F.Mask" "F.Paste")
			(net "P3V3")
		)
		(pad "2" smd circle
			(at 0.40005 0)
			(size 0 0)
			(layers "F.Cu" "F.Mask" "F.Paste")
			(net "PU_CLK_BUF_ISO_EN")
		)
	)
)
